# S9S_MB_2U (Grand Teton) — schematic netlist excerpt (pin names and nets, part order shuffled) for the footprints in the layout excerpt that follows; sources: Cadence DE-HDL packaged netlist, KiCad conversion of 03242023_DA0F0TMBIJ0_F0T_Motherboard_J_brd_V01_OCP.brd

PC494_P1_7  Q_CAP  22UF 16V 20% X6S  pkg C0805  page 288 : A = SW_P12V_PVCCIN_CPU1_FLT ; B = GND
R3062  Q_RES  2K 1% EMPTY  pkg 0402LF  page 241 : A = SMB_HOST_3V3AUX_SDA ; B = P3V3_AUX
PC406_P1_2  Q_CAP  22UF 16V 20% X6S  pkg C0805  page 289 : A = SW_P12V_PVCCFA_EHV_FIVRA_CPU1_L ; B = GND

(kicad_pcb
	(version 20260206)
	(generator "pcbnew")
	(generator_version "10.0")
	(general
		(thickness 1.6)
		(legacy_teardrops no)
	)
	(paper "A4")
	(title_block
		(title "03242023_DA0F0TMBIJ0_F0T_Motherboard_J_brd_V01_OCP.brd")
		(comment 1 "Grand Teton / footprints 4248-4251 of 6105")
	)
	(layers
		(0 "F.Cu" signal "TOP")
		(4 "In1.Cu" signal "GND")
		(6 "In2.Cu" signal "IN1")
		(8 "In3.Cu" signal "GND1")
		(10 "In4.Cu" signal "IN2")
		(12 "In5.Cu" signal "GND2")
		(14 "In6.Cu" signal "IN3")
		(16 "In7.Cu" signal "GND3")
		(18 "In8.Cu" signal "VCC")
		(20 "In9.Cu" signal "VCC1")
		(22 "In10.Cu" signal "GND4")
		(24 "In11.Cu" signal "IN4")
		(26 "In12.Cu" signal "GND5")
		(28 "In13.Cu" signal "IN5")
		(30 "In14.Cu" signal "GND6")
		(32 "In15.Cu" signal "IN6")
		(34 "In16.Cu" signal "GND7")
		(2 "B.Cu" signal "BOTTOM")
		(9 "F.Adhes" user "F.Adhesive")
		(11 "B.Adhes" user "B.Adhesive")
		(13 "F.Paste" user "Package Geometry/Pastemask Top")
		(15 "B.Paste" user "Package Geometry/Pastemask Bottom")
		(5 "F.SilkS" user "Ref Des/Silkscreen Top")
		(7 "B.SilkS" user "Ref Des/Silkscreen Bottom")
		(1 "F.Mask" user "Board Geometry/Soldermask Top")
		(3 "B.Mask" user "Board Geometry/Soldermask Bottom")
		(17 "Dwgs.User" user "User.Drawings")
		(19 "Cmts.User" user "User.Comments")
		(21 "Eco1.User" user "User.Eco1")
		(23 "Eco2.User" user "User.Eco2")
		(25 "Edge.Cuts" user "Board Geometry/Outline")
		(27 "Margin" user)
		(31 "F.CrtYd" user "Package Geometry/Place Bound Top")
		(29 "B.CrtYd" user "Package Geometry/Place Bound Bottom")
		(35 "F.Fab" user "Ref Des/Assembly Top")
		(33 "B.Fab" user "Ref Des/Assembly Bottom")
	)
	(footprint ""
		(layer "B.Cu")
		(at 54.510178 -353.567492 90)
		(property "Reference" "PC406_P1_2"
			(at 0 0 90)
			(layer "B.SilkS")
			(hide yes)
			(effects
				(font
					(size 1.27 1.27)
				)
				(justify mirror)
			)
		)
		(property "Value" ""
			(at 0 0 90)
			(layer "B.Fab")
			(effects
				(font
					(size 1.27 1.27)
				)
				(justify mirror)
			)
		)
		(duplicate_pad_numbers_are_jumpers no)
		(fp_line
			(start 1.524 -0.762)
			(end -1.524 -0.762)
			(stroke
				(width 0.1524)
				(type default)
			)
			(layer "B.SilkS")
		)
		(fp_line
			(start -1.524 -0.762)
			(end -1.524 0.762)
			(stroke
				(width 0.1524)
				(type default)
			)
			(layer "B.SilkS")
		)
		(fp_line
			(start 1.524 0.762)
			(end 1.524 -0.762)
			(stroke
				(width 0.1524)
				(type default)
			)
			(layer "B.SilkS")
		)
		(fp_line
			(start -1.524 0.762)
			(end 1.524 0.762)
			(stroke
				(width 0.1524)
				(type default)
			)
			(layer "B.SilkS")
		)
		(fp_line
			(start 1.1049 -0.724916)
			(end 1.1049 0.724916)
			(stroke
				(width 0.1)
				(type default)
			)
			(layer "B.Fab")
		)
		(fp_line
			(start -1.1049 -0.724916)
			(end 1.1049 -0.724916)
			(stroke
				(width 0.1)
				(type default)
			)
			(layer "B.Fab")
		)
		(fp_line
			(start 1.1049 0.724916)
			(end -1.1049 0.724916)
			(stroke
				(width 0.1)
				(type default)
			)
			(layer "B.Fab")
		)
		(fp_line
			(start -1.1049 0.724916)
			(end -1.1049 -0.724916)
			(stroke
				(width 0.1)
				(type default)
			)
			(layer "B.Fab")
		)
		(pad "1" smd rect
			(at 0.889 0 90)
			(size 1.016 1.27)
			(layers "B.Cu" "B.Mask" "B.Paste")
			(net "SW_P12V_PVCCFA_EHV_FIVRA_CPU1_L")
		)
		(pad "2" smd rect
			(at -0.889 0 90)
			(size 1.016 1.27)
			(layers "B.Cu" "B.Mask" "B.Paste")
			(net "GND")
		)
	)
	(footprint ""
		(layer "B.Cu")
		(at 81.798414 -342.936576 90)
		(property "Reference" "PC494_P1_7"
			(at 0 0 90)
			(layer "B.SilkS")
			(hide yes)
			(effects
				(font
					(size 1.27 1.27)
				)
				(justify mirror)
			)
		)
		(property "Value" ""
			(at 0 0 90)
			(layer "B.Fab")
			(effects
				(font
					(size 1.27 1.27)
				)
				(justify mirror)
			)
		)
		(duplicate_pad_numbers_are_jumpers no)
		(fp_line
			(start 1.524 -0.762)
			(end -1.524 -0.762)
			(stroke
				(width 0.1524)
				(type default)
			)
			(layer "B.SilkS")
		)
		(fp_line
			(start -1.524 -0.762)
			(end -1.524 0.762)
			(stroke
				(width 0.1524)
				(type default)
			)
			(layer "B.SilkS")
		)
		(fp_line
			(start 1.524 0.762)
			(end 1.524 -0.762)
			(stroke
				(width 0.1524)
				(type default)
			)
			(layer "B.SilkS")
		)
		(fp_line
			(start -1.524 0.762)
			(end 1.524 0.762)
			(stroke
				(width 0.1524)
				(type default)
			)
			(layer "B.SilkS")
		)
		(fp_line
			(start 1.1049 -0.724916)
			(end 1.1049 0.724916)
			(stroke
				(width 0.1)
				(type default)
			)
			(layer "B.Fab")
		)
		(fp_line
			(start -1.1049 -0.724916)
			(end 1.1049 -0.724916)
			(stroke
				(width 0.1)
				(type default)
			)
			(layer "B.Fab")
		)
		(fp_line
			(start 1.1049 0.724916)
			(end -1.1049 0.724916)
			(stroke
				(width 0.1)
				(type default)
			)
			(layer "B.Fab")
		)
		(fp_line
			(start -1.1049 0.724916)
			(end -1.1049 -0.724916)
			(stroke
				(width 0.1)
				(type default)
			)
			(layer "B.Fab")
		)
		(pad "1" smd rect
			(at 0.889 0 90)
			(size 1.016 1.27)
			(layers "B.Cu" "B.Mask" "B.Paste")
			(net "SW_P12V_PVCCIN_CPU1_FLT")
		)
		(pad "2" smd rect
			(at -0.889 0 90)
			(size 1.016 1.27)
			(layers "B.Cu" "B.Mask" "B.Paste")
			(net "GND")
		)
	)
	(footprint ""
		(layer "B.Cu")
		(at 180.8734 -21.364448 -90)
		(property "Reference" "R3062"
			(at 0 0 90)
			(layer "B.SilkS")
			(hide yes)
			(effects
				(font
					(size 1.27 1.27)
				)
				(justify mirror)
			)
		)
		(property "Value" ""
			(at 0 0 90)
			(layer "B.Fab")
			(effects
				(font
					(size 1.27 1.27)
				)
				(justify mirror)
			)
		)
		(duplicate_pad_numbers_are_jumpers no)
		(fp_line
			(start -0.7874 0.4064)
			(end 0.7874 0.4064)
			(stroke
				(width 0.1524)
				(type default)
			)
			(layer "B.SilkS")
		)
		(fp_line
			(start 0.7874 0.4064)
			(end 0.7874 -0.4064)
			(stroke
				(width 0.1524)
				(type default)
			)
			(layer "B.SilkS")
		)
		(fp_line
			(start -0.7874 -0.4064)
			(end -0.7874 0.4064)
			(stroke
				(width 0.1524)
				(type default)
			)
			(layer "B.SilkS")
		)
		(fp_line
			(start 0.7874 -0.4064)
			(end -0.7874 -0.4064)
			(stroke
				(width 0.1524)
				(type default)
			)
			(layer "B.SilkS")
		)
		(fp_line
			(start -0.67945 0.3048)
			(end -0.120396 0.3048)
			(stroke
				(width 0.1)
				(type default)
			)
			(layer "B.Fab")
		)
		(fp_line
			(start -0.120396 0.3048)
			(end -0.120396 0.2794)
			(stroke
				(width 0.1)
				(type default)
			)
			(layer "B.Fab")
		)
		(fp_line
			(start 0.12065 0.3048)
			(end 0.67945 0.3048)
			(stroke
				(width 0.1)
				(type default)
			)
			(layer "B.Fab")
		)
		(fp_line
			(start 0.67945 0.3048)
			(end 0.67945 -0.305054)
			(stroke
				(width 0.1)
				(type default)
			)
			(layer "B.Fab")
		)
		(fp_line
			(start -0.120396 0.2794)
			(end 0.12065 0.2794)
			(stroke
				(width 0.1)
				(type default)
			)
			(layer "B.Fab")
		)
		(fp_line
			(start 0.12065 0.2794)
			(end 0.12065 0.3048)
			(stroke
				(width 0.1)
				(type default)
			)
			(layer "B.Fab")
		)
		(fp_line
			(start -0.12065 -0.2794)
			(end -0.12065 -0.3048)
			(stroke
				(width 0.1)
				(type default)
			)
			(layer "B.Fab")
		)
		(fp_line
			(start 0.12065 -0.2794)
			(end -0.12065 -0.2794)
			(stroke
				(width 0.1)
				(type default)
			)
			(layer "B.Fab")
		)
		(fp_line
			(start -0.67945 -0.3048)
			(end -0.67945 0.3048)
			(stroke
				(width 0.1)
				(type default)
			)
			(layer "B.Fab")
		)
		(fp_line
			(start -0.12065 -0.3048)
			(end -0.67945 -0.3048)
			(stroke
				(width 0.1)
				(type default)
			)
			(layer "B.Fab")
		)
		(fp_line
			(start 0.12065 -0.305054)
			(end 0.12065 -0.2794)
			(stroke
				(width 0.1)
				(type default)
			)
			(layer "B.Fab")
		)
		(fp_line
			(start 0.67945 -0.305054)
			(end 0.12065 -0.305054)
			(stroke
				(width 0.1)
				(type default)
			)
			(layer "B.Fab")
		)
		(pad "1" smd circle
			(at 0.40005 0 90)
			(size 0 0)
			(layers "B.Cu" "B.Mask" "B.Paste")
			(net "SMB_HOST_3V3AUX_SDA")
		)
		(pad "2" smd circle
			(at -0.40005 0 90)
			(size 0 0)
			(layers "B.Cu" "B.Mask" "B.Paste")
			(net "P3V3_AUX")
		)
	)
	(footprint ""
		(layer "B.Cu")
		(at 438.4802 -434.365908)
		(property "Reference" ""
			(at 0 0 0)
			(layer "B.SilkS")
			(hide yes)
			(effects
				(font
					(size 1.27 1.27)
				)
				(justify mirror)
			)
		)
		(property "Value" ""
			(at 0 0 0)
			(layer "B.Fab")
			(effects
				(font
					(size 1.27 1.27)
				)
				(justify mirror)
			)
		)
		(duplicate_pad_numbers_are_jumpers no)
		(pad "1" smd circle
			(at 0 0 180)
			(size 0.9906 0.9906)
			(layers "B.Cu" "B.Mask" "B.Paste")
			(net "Net_287")
		)
		(zone
			(layer "B.Cu")
			(hatch none 0.5)
			(connect_pads
				(clearance 0)
			)
			(min_thickness 0.25)
			(keepout
				(tracks not_allowed)
				(vias allowed)
				(pads allowed)
				(copperpour not_allowed)
				(footprints allowed)
			)
			(placement
				(enabled no)
				(sheetname "")
			)
			(fill
				(thermal_gap 0.5)
				(thermal_bridge_width 0.5)
				(island_removal_mode 0)
			)
			(polygon
				(pts
					(arc
						(start 440.1058 -434.365908)
						(mid 436.8546 -434.365908)
						(end 440.1058 -434.365908)
					)
				)
			)
		)
	)
)
